FILE_TYPE = CONNECTIVITY;
{Allegro Design Entry HDL 16.6-p007 (v16-6-112F) 10/10/2012}
"PAGE_NUMBER" = 45;
0"NC";
1"M_B_DQS_DN<17:0>";
2"M_B_DQS_DP<17:0>";
3"M_B_MA<17:0>";
4"M_B_DQ<63:0>";
5"M_B_BG<1:0>";
6"M_B_CLK_DN<3:0>";
7"M_B_ECC<7:0>";
8"M_B_CLK_DP<3:0>";
9"M_B_CS_N<7:0>";
10"M_B_CKE<3:0>";
11"M_B_BA<1:0>";
12"M_B_ODT<3:0>";
13"PVTT_ABC\g";
14"PVDDQ_ABC\g";
15"GND\g";
16"GND\g";
17"PVPP_ABC\g";
18"PVPP_ABC\g";
19"P12V_NVDIMM_ABC\g";
20"GND\g";
21"GND\g";
22"FM_DIMM_EVENT_COD_N";
23"M_B_VREF";
24"TP_CH_B_DIMM_B0_RFU_1";
25"TP_CH_B_DIMM_B0_RFU_0";
26"TP_CH_B_DIMM_B0_RFU_2";
27"M_B_ALERT_N";
28"M_B_ACT_N";
29"SMB_DDR_ABC_VPP_SDA";
30"SMB_DDR_ABC_VPP_SCL";
31"FM_ADR_COMPLETE_ABC_N";
32"M_ABC_RST_N";
33"M_B_PAR";
34"M_B_C<2>";
35"M_B_CS_N<0>";
36"M_B_CKE<0>";
37"M_B_ODT<1>";
38"M_B_ODT<0>";
39"M_B_ECC<6>";
40"M_B_MA<2>";
41"M_B_BA<0>";
42"M_B_BG<1>";
43"M_B_CLK_DP<1>";
44"M_B_CKE<1>";
45"M_B_ECC<0>";
46"M_B_ECC<3>";
47"M_B_ECC<2>";
48"M_B_ECC<5>";
49"M_B_ECC<4>";
50"M_B_ECC<7>";
51"M_B_MA<6>";
52"M_B_MA<5>";
53"M_B_MA<4>";
54"M_B_MA<3>";
55"M_B_MA<1>";
56"M_B_MA<0>";
57"M_B_CS_N<1>";
58"M_B_CS_N<2>";
59"M_B_CS_N<3>";
60"M_B_CLK_DP<0>";
61"M_B_BA<1>";
62"M_B_ECC<1>";
63"M_B_CLK_DN<0>";
64"M_B_CLK_DN<1>";
65"M_B_BG<0>";
66"M_B_DQ<1>";
67"M_B_DQ<0>";
68"M_B_DQ<4>";
69"M_B_DQ<5>";
70"M_B_DQ<2>";
71"M_B_DQ<3>";
72"M_B_DQ<7>";
73"M_B_DQ<9>";
74"M_B_DQ<8>";
75"M_B_DQ<11>";
76"M_B_DQ<10>";
77"M_B_DQ<6>";
78"M_B_DQ<16>";
79"M_B_DQ<14>";
80"M_B_DQ<13>";
81"M_B_DQ<12>";
82"M_B_DQ<15>";
83"M_B_DQ<17>";
84"M_B_DQ<19>";
85"M_B_DQ<18>";
86"M_B_DQ<20>";
87"M_B_DQ<23>";
88"M_B_DQ<21>";
89"M_B_DQ<27>";
90"M_B_DQ<26>";
91"M_B_DQ<22>";
92"M_B_DQ<25>";
93"M_B_DQ<24>";
94"M_B_DQ<31>";
95"M_B_DQ<30>";
96"M_B_DQ<33>";
97"M_B_DQ<29>";
98"M_B_DQ<28>";
99"M_B_DQ<39>";
100"M_B_DQ<37>";
101"M_B_DQ<34>";
102"M_B_DQ<32>";
103"M_B_DQ<35>";
104"M_B_DQ<36>";
105"M_B_DQ<38>";
106"M_B_DQ<41>";
107"M_B_DQ<40>";
108"M_B_DQ<43>";
109"M_B_DQ<46>";
110"M_B_DQ<49>";
111"M_B_DQ<48>";
112"M_B_DQ<51>";
113"M_B_DQ<50>";
114"M_B_DQ<53>";
115"M_B_DQ<42>";
116"M_B_DQ<45>";
117"M_B_DQ<44>";
118"M_B_DQ<47>";
119"M_B_MA<16>";
120"M_B_MA<15>";
121"M_B_MA<14>";
122"M_B_MA<11>";
123"M_B_MA<10>";
124"M_B_MA<9>";
125"M_B_MA<8>";
126"M_B_MA<7>";
127"M_B_MA<17>";
128"M_B_MA<13>";
129"M_B_MA<12>";
130"M_B_DQ<62>";
131"M_B_DQ<63>";
132"M_B_DQ<60>";
133"M_B_DQ<52>";
134"M_B_DQ<55>";
135"M_B_DQ<59>";
136"M_B_DQ<56>";
137"M_B_DQ<54>";
138"M_B_DQ<57>";
139"M_B_DQ<58>";
140"M_B_DQ<61>";
141"M_B_DQS_DP<6>";
142"M_B_DQS_DN<6>";
143"M_B_DQS_DP<5>";
144"M_B_DQS_DN<5>";
145"M_B_DQS_DP<4>";
146"M_B_DQS_DN<4>";
147"M_B_DQS_DP<3>";
148"M_B_DQS_DN<3>";
149"M_B_DQS_DP<2>";
150"M_B_DQS_DN<2>";
151"M_B_DQS_DP<1>";
152"M_B_DQS_DN<1>";
153"M_B_DQS_DP<0>";
154"M_B_DQS_DN<0>";
155"M_B_DQS_DP<9>";
156"M_B_DQS_DN<9>";
157"M_B_DQS_DP<8>";
158"M_B_DQS_DN<8>";
159"M_B_DQS_DP<7>";
160"M_B_DQS_DN<7>";
161"M_B_DQS_DN<17>";
162"M_B_DQS_DP<16>";
163"M_B_DQS_DN<16>";
164"M_B_DQS_DP<15>";
165"M_B_DQS_DN<15>";
166"M_B_DQS_DP<14>";
167"M_B_DQS_DN<14>";
168"M_B_DQS_DP<13>";
169"M_B_DQS_DN<13>";
170"M_B_DQS_DP<12>";
171"M_B_DQS_DN<12>";
172"M_B_DQS_DP<11>";
173"M_B_DQS_DN<11>";
174"M_B_DQS_DP<10>";
175"M_B_DQS_DN<10>";
176"M_B_DQS_DP<17>";
%"TAP"
"6","(700,4850)","2","mstr_standard","I10";
;
HDL_TAP"TRUE"
BODY_TYPE"PLUMBING"
CDS_LIB"mstr_standard";
"B \NAC \NWC"2;
"S \NAC"
BN"14"166;
%"TAP"
"6","(-1700,1850)","2","mstr_standard","I100";
;
HDL_TAP"TRUE"
BODY_TYPE"PLUMBING"
CDS_LIB"mstr_standard";
"B \NAC \NWC"4;
"S \NAC"
BN"9"73;
%"TAP"
"6","(-1700,1950)","2","mstr_standard","I101";
;
HDL_TAP"TRUE"
BODY_TYPE"PLUMBING"
CDS_LIB"mstr_standard";
"B \NAC \NWC"4;
"S \NAC"
BN"11"75;
%"TAP"
"6","(-1700,1900)","2","mstr_standard","I102";
;
HDL_TAP"TRUE"
BODY_TYPE"PLUMBING"
CDS_LIB"mstr_standard";
"B \NAC \NWC"4;
"S \NAC"
BN"8"74;
%"TAP"
"6","(-1700,1700)","2","mstr_standard","I103";
;
HDL_TAP"TRUE"
BODY_TYPE"PLUMBING"
CDS_LIB"mstr_standard";
"B \NAC \NWC"4;
"S \NAC"
BN"4"68;
%"TAP"
"6","(-1700,1750)","2","mstr_standard","I104";
;
HDL_TAP"TRUE"
BODY_TYPE"PLUMBING"
CDS_LIB"mstr_standard";
"B \NAC \NWC"4;
"S \NAC"
BN"7"72;
%"TAP"
"6","(-1700,1800)","2","mstr_standard","I105";
;
HDL_TAP"TRUE"
BODY_TYPE"PLUMBING"
CDS_LIB"mstr_standard";
"B \NAC \NWC"4;
"S \NAC"
BN"6"77;
%"TAP"
"6","(-1700,1650)","2","mstr_standard","I106";
;
HDL_TAP"TRUE"
BODY_TYPE"PLUMBING"
CDS_LIB"mstr_standard";
"B \NAC \NWC"4;
"S \NAC"
BN"5"69;
%"TAP"
"6","(-1700,1600)","2","mstr_standard","I107";
;
HDL_TAP"TRUE"
BODY_TYPE"PLUMBING"
CDS_LIB"mstr_standard";
"B \NAC \NWC"4;
"S \NAC"
BN"2"70;
%"TAP"
"6","(-1700,1500)","2","mstr_standard","I108";
;
HDL_TAP"TRUE"
BODY_TYPE"PLUMBING"
CDS_LIB"mstr_standard";
"B \NAC \NWC"4;
"S \NAC"
BN"0"67;
%"TAP"
"6","(-1700,1550)","2","mstr_standard","I109";
;
HDL_TAP"TRUE"
BODY_TYPE"PLUMBING"
CDS_LIB"mstr_standard";
"B \NAC \NWC"4;
"S \NAC"
BN"3"71;
%"TAP"
"6","(-1700,1450)","2","mstr_standard","I110";
;
HDL_TAP"TRUE"
BODY_TYPE"PLUMBING"
CDS_LIB"mstr_standard";
"B \NAC \NWC"4;
"S \NAC"
BN"1"66;
%"SCONN288_H44441004"
"1","(-2450,2950)","0","mstr_sconn","I111";
;
CDS_SEC"1"
ROOM"DDR4_CH_B"
CDS_LOCATION"J4G2"
SEC"1"
SEC_TYPE"PIP"
CDS_LIB"mstr_sconn"
BOM_COST"MEM"
PACK_TYPE"PIP"
MATERIAL"SCONN"
PART_NUMBER"H44441-004"
LOCATION"J4G2";
"DQ<63>"
$PN"280"130;
"DQ<62>"
$PN"135"131;
"DQ<61>"
$PN"273"132;
"DQ<5>"
$PN"148"68;
"DQ<4>"
$PN"3"69;
"DQ<3>"
$PN"157"70;
"DQ<2>"
$PN"12"71;
"DQ<47>"
$PN"258"109;
"DQ<48>"
$PN"119"110;
"DQ<49>"
$PN"264"111;
"DQ<50>"
$PN"126"112;
"DQ<51>"
$PN"271"113;
"DQ<52>"
$PN"117"114;
"DQ<53>"
$PN"262"133;
"DQ<54>"
$PN"124"134;
"DQ<58>"
$PN"137"135;
"DQ<57>"
$PN"275"136;
"SAVE_N_NC"
$PN"230"31;
"RFU<1>"
$PN"227"24;
"RFU<0>"
$PN"205"25;
"DQ<17>"
$PN"172"78;
"DQ<15>"
$PN"166"79;
"DQ<26>"
$PN"45"89;
"DQ<27>"
$PN"190"90;
"S0_N"
$PN"84"35;
"CKE<0>"
$PN"60"36;
"ODT<1>"
$PN"91"37;
"ODT<0>"
$PN"87"38;
"CB<7>"
$PN"199"39;
"A16_RAS_N"
$PN"82"119;
"A15_CAS_N"
$PN"86"120;
"A14_WE_N"
$PN"228"121;
"A11"
$PN"210"122;
"A10"
$PN"225"123;
"DQ<38>"
$PN"102"99;
"DQ<36>"
$PN"95"100;
"DQ<35>"
$PN"249"101;
"A2"
$PN"216"40;
"ALERT_N"
$PN"208"27;
"ACT_N"
$PN"62"28;
"DQ<0>"
$PN"5"66;
"DQ<1>"
$PN"150"67;
"SA<1>"
$PN"140"18;
"SA<2>"
$PN"238"15;
"VDDSPD"
$PN"284"18;
"SA<0>"
$PN"139"15;
"BA<0>"
$PN"81"41;
"BG<1>"
$PN"207"42;
"BG<0>"
$PN"63"65;
"CK1P"
$PN"218"43;
"VREFCA"
$PN"146"23;
"SDA"
$PN"285"29;
"SCL"
$PN"141"30;
"RFU<2>"
$PN"144"26;
"RESET_N"
$PN"58"32;
"PAR"
$PN"222"33;
"EVENT_N"
$PN"78"22;
"DQ<6>"
$PN"10"72;
"DQ<7>"
$PN"155"77;
"DQ<8>"
$PN"16"73;
"DQ<9>"
$PN"161"74;
"DQ<10>"
$PN"23"75;
"DQ<11>"
$PN"168"76;
"DQ<12>"
$PN"14"80;
"DQ<13>"
$PN"159"81;
"DQ<14>"
$PN"21"82;
"DQ<16>"
$PN"27"83;
"DQ<18>"
$PN"34"84;
"DQ<19>"
$PN"179"85;
"DQ<20>"
$PN"25"88;
"DQ<21>"
$PN"170"86;
"DQ<22>"
$PN"32"87;
"DQ<23>"
$PN"177"91;
"DQ<24>"
$PN"38"92;
"DQ<25>"
$PN"183"93;
"DQ<30>"
$PN"43"94;
"DQ<31>"
$PN"188"95;
"DQ<32>"
$PN"97"96;
"DQ<33>"
$PN"242"102;
"DQ<34>"
$PN"104"103;
"DQ<37>"
$PN"240"104;
"DQ<39>"
$PN"247"105;
"DQ<40>"
$PN"108"106;
"DQ<41>"
$PN"253"107;
"DQ<42>"
$PN"115"108;
"DQ<43>"
$PN"260"115;
"DQ<44>"
$PN"106"116;
"DQ<45>"
$PN"251"117;
"DQ<46>"
$PN"113"118;
"DQ<55>"
$PN"269"137;
"DQ<56>"
$PN"130"138;
"DQ<59>"
$PN"282"139;
"DQ<60>"
$PN"128"140;
"CKE<1>"
$PN"203"44;
"CK0N"
$PN"75"63;
"CB<0>"
$PN"49"62;
"CB<1>"
$PN"194"45;
"CB<2>"
$PN"56"46;
"CB<3>"
$PN"201"47;
"CB<4>"
$PN"47"48;
"CB<5>"
$PN"192"49;
"CB<6>"
$PN"54"50;
"A9"
$PN"66"124;
"A8"
$PN"68"125;
"A7"
$PN"211"126;
"A6"
$PN"69"51;
"A5"
$PN"213"52;
"A4"
$PN"214"53;
"A3"
$PN"71"54;
"A17"
$PN"234"127;
"A13"
$PN"232"128;
"A12"
$PN"65"129;
"A1"
$PN"72"55;
"A0"
$PN"79"56;
"C<2>"
$PN"235"34;
"DQ<28>"
$PN"36"97;
"DQ<29>"
$PN"181"98;
"S1_N"
$PN"89"57;
"S2_N_C<0>"
$PN"93"58;
"S3_N_C<1>"
$PN"237"59;
"CK0P"
$PN"74"60;
"CK1N"
$PN"219"64;
"BA<1>"
$PN"224"61;
%"TAP"
"6","(-3200,4600)","0","mstr_standard","I112";
;
HDL_TAP"TRUE"
BODY_TYPE"PLUMBING"
CDS_LIB"mstr_standard";
"B \NAC \NWC"3;
"S \NAC"
BN"17"127;
%"TAP"
"6","(-3200,4550)","0","mstr_standard","I113";
;
HDL_TAP"TRUE"
BODY_TYPE"PLUMBING"
CDS_LIB"mstr_standard";
"B \NAC \NWC"3;
"S \NAC"
BN"16"119;
%"TAP"
"6","(-3200,4500)","0","mstr_standard","I114";
;
HDL_TAP"TRUE"
BODY_TYPE"PLUMBING"
CDS_LIB"mstr_standard";
"B \NAC \NWC"3;
"S \NAC"
BN"15"120;
%"TAP"
"6","(-3200,4450)","0","mstr_standard","I115";
;
HDL_TAP"TRUE"
BODY_TYPE"PLUMBING"
CDS_LIB"mstr_standard";
"B \NAC \NWC"3;
"S \NAC"
BN"14"121;
%"TAP"
"6","(-3200,4400)","0","mstr_standard","I116";
;
HDL_TAP"TRUE"
BODY_TYPE"PLUMBING"
CDS_LIB"mstr_standard";
"B \NAC \NWC"3;
"S \NAC"
BN"13"128;
%"TAP"
"6","(-3200,4350)","0","mstr_standard","I117";
;
HDL_TAP"TRUE"
BODY_TYPE"PLUMBING"
CDS_LIB"mstr_standard";
"B \NAC \NWC"3;
"S \NAC"
BN"12"129;
%"TAP"
"6","(-3200,4300)","0","mstr_standard","I118";
;
HDL_TAP"TRUE"
BODY_TYPE"PLUMBING"
CDS_LIB"mstr_standard";
"B \NAC \NWC"3;
"S \NAC"
BN"11"122;
%"TAP"
"6","(-3200,4250)","0","mstr_standard","I119";
;
HDL_TAP"TRUE"
BODY_TYPE"PLUMBING"
CDS_LIB"mstr_standard";
"B \NAC \NWC"3;
"S \NAC"
BN"10"123;
%"PVTT_ABC"
"1","(-800,2700)","0","mstr_symbols","I12";
;
HDL_POWER"PVTT_ABC"
ROOM"DDR4_CH_A"
BODY_TYPE"PLUMBING"
CDS_LIB"mstr_symbols"
BOM_COST"MEM"
VOLTAGE"0.6V";
"G\NAC"13;
%"TAP"
"6","(-3200,4200)","0","mstr_standard","I120";
;
HDL_TAP"TRUE"
BODY_TYPE"PLUMBING"
CDS_LIB"mstr_standard";
"B \NAC \NWC"3;
"S \NAC"
BN"9"124;
%"TAP"
"6","(-3200,4150)","0","mstr_standard","I121";
;
HDL_TAP"TRUE"
BODY_TYPE"PLUMBING"
CDS_LIB"mstr_standard";
"B \NAC \NWC"3;
"S \NAC"
BN"8"125;
%"TAP"
"6","(-3200,4100)","0","mstr_standard","I122";
;
HDL_TAP"TRUE"
BODY_TYPE"PLUMBING"
CDS_LIB"mstr_standard";
"B \NAC \NWC"3;
"S \NAC"
BN"7"126;
%"TAP"
"6","(-3200,4050)","0","mstr_standard","I123";
;
HDL_TAP"TRUE"
BODY_TYPE"PLUMBING"
CDS_LIB"mstr_standard";
"B \NAC \NWC"3;
"S \NAC"
BN"6"51;
%"TAP"
"6","(-3200,4000)","0","mstr_standard","I124";
;
HDL_TAP"TRUE"
BODY_TYPE"PLUMBING"
CDS_LIB"mstr_standard";
"B \NAC \NWC"3;
"S \NAC"
BN"5"52;
%"TAP"
"6","(-3200,3950)","0","mstr_standard","I125";
;
HDL_TAP"TRUE"
BODY_TYPE"PLUMBING"
CDS_LIB"mstr_standard";
"B \NAC \NWC"3;
"S \NAC"
BN"4"53;
%"TAP"
"6","(-3200,3900)","0","mstr_standard","I126";
;
HDL_TAP"TRUE"
BODY_TYPE"PLUMBING"
CDS_LIB"mstr_standard";
"B \NAC \NWC"3;
"S \NAC"
BN"3"54;
%"TAP"
"6","(-3200,3850)","0","mstr_standard","I128";
;
HDL_TAP"TRUE"
BODY_TYPE"PLUMBING"
CDS_LIB"mstr_standard";
"B \NAC \NWC"3;
"S \NAC"
BN"2"40;
%"TAP"
"6","(-3200,3800)","0","mstr_standard","I129";
;
HDL_TAP"TRUE"
BODY_TYPE"PLUMBING"
CDS_LIB"mstr_standard";
"B \NAC \NWC"3;
"S \NAC"
BN"1"55;
%"PVDDQ_ABC"
"1","(-1025,2550)","0","mstr_symbols","I13";
;
HDL_POWER"PVDDQ_ABC"
ROOM"DDR4_CH_A"
BODY_TYPE"PLUMBING"
CDS_LIB"mstr_symbols"
BOM_COST"MEM"
VOLTAGE"1.2V";
"G\NAC"14;
%"TAP"
"6","(-3200,3750)","0","mstr_standard","I130";
;
HDL_TAP"TRUE"
BODY_TYPE"PLUMBING"
CDS_LIB"mstr_standard";
"B \NAC \NWC"3;
"S \NAC"
BN"0"56;
%"TAP"
"6","(-3200,3650)","0","mstr_standard","I131";
;
HDL_TAP"TRUE"
BODY_TYPE"PLUMBING"
CDS_LIB"mstr_standard";
"B \NAC \NWC"11;
"S \NAC"
BN"1"61;
%"TAP"
"6","(-3200,3600)","0","mstr_standard","I132";
;
HDL_TAP"TRUE"
BODY_TYPE"PLUMBING"
CDS_LIB"mstr_standard";
"B \NAC \NWC"11;
"S \NAC"
BN"0"41;
%"TAP"
"6","(-3200,3500)","0","mstr_standard","I133";
;
HDL_TAP"TRUE"
BODY_TYPE"PLUMBING"
CDS_LIB"mstr_standard";
"B \NAC \NWC"5;
"S \NAC"
BN"0"65;
%"TAP"
"6","(-3200,3550)","0","mstr_standard","I134";
;
HDL_TAP"TRUE"
BODY_TYPE"PLUMBING"
CDS_LIB"mstr_standard";
"B \NAC \NWC"5;
"S \NAC"
BN"1"42;
%"TAP"
"6","(-3200,2550)","0","mstr_standard","I138";
;
HDL_TAP"TRUE"
BODY_TYPE"PLUMBING"
CDS_LIB"mstr_standard";
"B \NAC \NWC"7;
"S \NAC"
BN"6"39;
%"TAP"
"6","(-3200,2500)","0","mstr_standard","I139";
;
HDL_TAP"TRUE"
BODY_TYPE"PLUMBING"
CDS_LIB"mstr_standard";
"B \NAC \NWC"7;
"S \NAC"
BN"7"50;
%"TAP"
"6","(900,4600)","2","mstr_standard","I14";
;
HDL_TAP"TRUE"
BODY_TYPE"PLUMBING"
CDS_LIB"mstr_standard";
"B \NAC \NWC"1;
"S \NAC"
BN"12"171;
%"TAP"
"6","(-3200,2450)","0","mstr_standard","I140";
;
HDL_TAP"TRUE"
BODY_TYPE"PLUMBING"
CDS_LIB"mstr_standard";
"B \NAC \NWC"7;
"S \NAC"
BN"4"49;
%"TAP"
"6","(-3200,2400)","0","mstr_standard","I141";
;
HDL_TAP"TRUE"
BODY_TYPE"PLUMBING"
CDS_LIB"mstr_standard";
"B \NAC \NWC"7;
"S \NAC"
BN"5"48;
%"TAP"
"6","(-3200,2350)","0","mstr_standard","I142";
;
HDL_TAP"TRUE"
BODY_TYPE"PLUMBING"
CDS_LIB"mstr_standard";
"B \NAC \NWC"7;
"S \NAC"
BN"2"47;
%"TAP"
"6","(-3200,2300)","0","mstr_standard","I143";
;
HDL_TAP"TRUE"
BODY_TYPE"PLUMBING"
CDS_LIB"mstr_standard";
"B \NAC \NWC"7;
"S \NAC"
BN"3"46;
%"TAP"
"6","(-3200,2250)","0","mstr_standard","I144";
;
HDL_TAP"TRUE"
BODY_TYPE"PLUMBING"
CDS_LIB"mstr_standard";
"B \NAC \NWC"7;
"S \NAC"
BN"0"45;
%"TAP"
"6","(-3200,2200)","0","mstr_standard","I145";
;
HDL_TAP"TRUE"
BODY_TYPE"PLUMBING"
CDS_LIB"mstr_standard";
"B \NAC \NWC"7;
"S \NAC"
BN"1"62;
%"TAP"
"6","(900,4700)","2","mstr_standard","I15";
;
HDL_TAP"TRUE"
BODY_TYPE"PLUMBING"
CDS_LIB"mstr_standard";
"B \NAC \NWC"1;
"S \NAC"
BN"13"169;
%"TAP"
"6","(-3200,2700)","0","mstr_standard","I152";
;
HDL_TAP"TRUE"
BODY_TYPE"PLUMBING"
CDS_LIB"mstr_standard";
"B \NAC \NWC"12;
"S \NAC"
BN"1"37;
%"TAP"
"6","(-3200,2650)","0","mstr_standard","I153";
;
HDL_TAP"TRUE"
BODY_TYPE"PLUMBING"
CDS_LIB"mstr_standard";
"B \NAC \NWC"12;
"S \NAC"
BN"0"38;
%"TAP"
"6","(-3200,2850)","0","mstr_standard","I155";
;
HDL_TAP"TRUE"
BODY_TYPE"PLUMBING"
CDS_LIB"mstr_standard";
"B \NAC \NWC"10;
"S \NAC"
BN"1"44;
%"TAP"
"6","(-3200,2800)","0","mstr_standard","I156";
;
HDL_TAP"TRUE"
BODY_TYPE"PLUMBING"
CDS_LIB"mstr_standard";
"B \NAC \NWC"10;
"S \NAC"
BN"0"36;
%"TAP"
"6","(-3200,3100)","0","mstr_standard","I158";
;
HDL_TAP"TRUE"
BODY_TYPE"PLUMBING"
CDS_LIB"mstr_standard";
"B \NAC \NWC"9;
"S \NAC"
BN"3"59;
%"TAP"
"6","(700,4750)","2","mstr_standard","I16";
;
HDL_TAP"TRUE"
BODY_TYPE"PLUMBING"
CDS_LIB"mstr_standard";
"B \NAC \NWC"2;
"S \NAC"
BN"13"168;
%"TAP"
"6","(-3200,3050)","0","mstr_standard","I160";
;
HDL_TAP"TRUE"
BODY_TYPE"PLUMBING"
CDS_LIB"mstr_standard";
"B \NAC \NWC"9;
"S \NAC"
BN"2"58;
%"TAP"
"6","(-3200,3000)","0","mstr_standard","I161";
;
HDL_TAP"TRUE"
BODY_TYPE"PLUMBING"
CDS_LIB"mstr_standard";
"B \NAC \NWC"9;
"S \NAC"
BN"1"57;
%"TAP"
"6","(-3200,2950)","0","mstr_standard","I162";
;
HDL_TAP"TRUE"
BODY_TYPE"PLUMBING"
CDS_LIB"mstr_standard";
"B \NAC \NWC"9;
"S \NAC"
BN"0"35;
%"TAP"
"6","(-3400,3350)","0","mstr_standard","I163";
;
HDL_TAP"TRUE"
BODY_TYPE"PLUMBING"
CDS_LIB"mstr_standard";
"B \NAC \NWC"6;
"S \NAC"
BN"1"64;
%"TAP"
"6","(-3400,3250)","0","mstr_standard","I164";
;
HDL_TAP"TRUE"
BODY_TYPE"PLUMBING"
CDS_LIB"mstr_standard";
"B \NAC \NWC"6;
"S \NAC"
BN"0"63;
%"TAP"
"6","(-3200,3300)","0","mstr_standard","I165";
;
HDL_TAP"TRUE"
BODY_TYPE"PLUMBING"
CDS_LIB"mstr_standard";
"B \NAC \NWC"8;
"S \NAC"
BN"0"60;
%"TAP"
"6","(-3200,3400)","0","mstr_standard","I166";
;
HDL_TAP"TRUE"
BODY_TYPE"PLUMBING"
CDS_LIB"mstr_standard";
"B \NAC \NWC"8;
"S \NAC"
BN"1"43;
%"SCONN288_H44441004"
"4","(50,2000)","0","mstr_sconn","I169";
;
CDS_SEC"4"
ROOM"DDR4_CH_B"
CDS_LOCATION"J4G2"
SEC"4"
SEC_TYPE"PIP"
CDS_LIB"mstr_sconn"
BOM_COST"MEM"
PACK_TYPE"PIP"
MATERIAL"SCONN"
PART_NUMBER"H44441-004"
LOCATION"J4G2";
"VPP<4>"
$PN"142"17;
"VTT<1>"
$PN"77"13;
"VPP<0>"
$PN"287"17;
"VPP<1>"
$PN"286"17;
"VPP<2>"
$PN"288"17;
"VPP<3>"
$PN"143"17;
"VDD<1>"
$PN"233"14;
"VDD<2>"
$PN"231"14;
"VDD<3>"
$PN"229"14;
"VDD<4>"
$PN"226"14;
"VDD<5>"
$PN"223"14;
"VDD<7>"
$PN"217"14;
"VDD<8>"
$PN"215"14;
"VDD<9>"
$PN"212"14;
"VDD<11>"
$PN"206"14;
"VDD<12>"
$PN"204"14;
"VDD<14>"
$PN"90"14;
"VDD<15>"
$PN"88"14;
"VDD<17>"
$PN"83"14;
"VDD<18>"
$PN"80"14;
"VDD<20>"
$PN"73"14;
"VDD<21>"
$PN"70"14;
"VDD<22>"
$PN"67"14;
"VDD<24>"
$PN"61"14;
"12V<0>"
$PN"145"19;
"12V<1>"
$PN"1"19;
"VTT<0>"
$PN"221"13;
"VDD<25>"
$PN"59"14;
"VDD<23>"
$PN"64"14;
"VDD<19>"
$PN"76"14;
"VDD<16>"
$PN"85"14;
"VDD<13>"
$PN"92"14;
"VDD<10>"
$PN"209"14;
"VDD<6>"
$PN"220"14;
"VDD<0>"
$PN"236"14;
%"TAP"
"6","(700,4650)","2","mstr_standard","I17";
;
HDL_TAP"TRUE"
BODY_TYPE"PLUMBING"
CDS_LIB"mstr_standard";
"B \NAC \NWC"2;
"S \NAC"
BN"12"170;
%"GND"
"1","(-5050,1600)","2","mstr_symbols","I174";
;
HDL_POWER"GND"
ROOM"DDR4_CH_A"
BODY_TYPE"PLUMBING"
SIZE"1B"
CDS_LIB"mstr_symbols"
BOM_COST"MEM"
VOLTAGE"0";
"A\NAC"15;
%"GND"
"1","(-4600,1000)","0","mstr_symbols","I178";
;
HDL_POWER"GND"
ROOM"DDR4_CH_A"
BODY_TYPE"PLUMBING"
BOM_COST"MEM"
SIZE"1B"
CDS_LIB"mstr_symbols"
VOLTAGE"0";
"A\NAC"16;
%"CAP_A"
"1","(-4600,1250)","2","dev_discrete","I179";
;
ROOM"DDR4_CH_A"
$SEC"1"
CDS_SEC"1"
CDS_LIB"dev_discrete"
BOM_COST"MEM"
CDS_LOCATION"C4G3"
MATERIAL"X7R"
VOLTAGE"25V"
PACK_TYPE"0402V"
TOLERANCE"10%"
VALUE"0.01UF"
PART_NUMBER"A36096-045"
LOCATION"C4G3";
"B"
$PN"2"16;
"A"
$PN"1"23;
%"TAP"
"6","(700,4550)","2","mstr_standard","I18";
;
HDL_TAP"TRUE"
BODY_TYPE"PLUMBING"
CDS_LIB"mstr_standard";
"B \NAC \NWC"2;
"S \NAC"
BN"11"172;
%"PVPP_ABC"
"1","(-650,3000)","0","mstr_symbols","I180";
;
HDL_POWER"PVPP_ABC"
ROOM"DDR4_CH_A"
BODY_TYPE"PLUMBING"
CDS_LIB"mstr_symbols"
BOM_COST"MEM"
VOLTAGE"2.5V";
"G\NAC"17;
%"PVPP_ABC"
"1","(-5050,1950)","0","mstr_symbols","I181";
;
HDL_POWER"PVPP_ABC"
ROOM"DDR4_CH_A"
BODY_TYPE"PLUMBING"
CDS_LIB"mstr_symbols"
BOM_COST"MEM"
VOLTAGE"2.5V";
"G\NAC"18;
%"P12V_NVDIMM_ABC"
"1","(750,3075)","0","mstr_symbols","I183";
;
HDL_POWER"P12V_NVDIMM_ABC"
BODY_TYPE"PLUMBING"
CDS_LIB"mstr_symbols"
VOLTAGE"12.0";
"G\NAC"19;
%"TAP"
"6","(900,4400)","2","mstr_standard","I19";
;
HDL_TAP"TRUE"
BODY_TYPE"PLUMBING"
CDS_LIB"mstr_standard";
"B \NAC \NWC"1;
"S \NAC"
BN"10"175;
%"TAP"
"6","(900,4500)","2","mstr_standard","I20";
;
HDL_TAP"TRUE"
BODY_TYPE"PLUMBING"
CDS_LIB"mstr_standard";
"B \NAC \NWC"1;
"S \NAC"
BN"11"173;
%"TAP"
"6","(900,4300)","2","mstr_standard","I21";
;
HDL_TAP"TRUE"
BODY_TYPE"PLUMBING"
CDS_LIB"mstr_standard";
"B \NAC \NWC"1;
"S \NAC"
BN"9"156;
%"TAP"
"6","(700,4450)","2","mstr_standard","I22";
;
HDL_TAP"TRUE"
BODY_TYPE"PLUMBING"
CDS_LIB"mstr_standard";
"B \NAC \NWC"2;
"S \NAC"
BN"10"174;
%"TAP"
"6","(700,4350)","2","mstr_standard","I23";
;
HDL_TAP"TRUE"
BODY_TYPE"PLUMBING"
CDS_LIB"mstr_standard";
"B \NAC \NWC"2;
"S \NAC"
BN"9"155;
%"TAP"
"6","(900,4100)","2","mstr_standard","I24";
;
HDL_TAP"TRUE"
BODY_TYPE"PLUMBING"
CDS_LIB"mstr_standard";
"B \NAC \NWC"1;
"S \NAC"
BN"7"160;
%"TAP"
"6","(900,4200)","2","mstr_standard","I25";
;
HDL_TAP"TRUE"
BODY_TYPE"PLUMBING"
CDS_LIB"mstr_standard";
"B \NAC \NWC"1;
"S \NAC"
BN"8"158;
%"TAP"
"6","(700,4250)","2","mstr_standard","I26";
;
HDL_TAP"TRUE"
BODY_TYPE"PLUMBING"
CDS_LIB"mstr_standard";
"B \NAC \NWC"2;
"S \NAC"
BN"8"157;
%"TAP"
"6","(700,4150)","2","mstr_standard","I27";
;
HDL_TAP"TRUE"
BODY_TYPE"PLUMBING"
CDS_LIB"mstr_standard";
"B \NAC \NWC"2;
"S \NAC"
BN"7"159;
%"TAP"
"6","(700,4050)","2","mstr_standard","I28";
;
HDL_TAP"TRUE"
BODY_TYPE"PLUMBING"
CDS_LIB"mstr_standard";
"B \NAC \NWC"2;
"S \NAC"
BN"6"141;
%"TAP"
"6","(900,3900)","2","mstr_standard","I29";
;
HDL_TAP"TRUE"
BODY_TYPE"PLUMBING"
CDS_LIB"mstr_standard";
"B \NAC \NWC"1;
"S \NAC"
BN"5"144;
%"TAP"
"6","(900,5100)","2","mstr_standard","I3";
;
HDL_TAP"TRUE"
BODY_TYPE"PLUMBING"
CDS_LIB"mstr_standard";
"B \NAC \NWC"1;
"S \NAC"
BN"17"161;
%"TAP"
"6","(900,4000)","2","mstr_standard","I30";
;
HDL_TAP"TRUE"
BODY_TYPE"PLUMBING"
CDS_LIB"mstr_standard";
"B \NAC \NWC"1;
"S \NAC"
BN"6"142;
%"TAP"
"6","(900,3800)","2","mstr_standard","I31";
;
HDL_TAP"TRUE"
BODY_TYPE"PLUMBING"
CDS_LIB"mstr_standard";
"B \NAC \NWC"1;
"S \NAC"
BN"4"146;
%"TAP"
"6","(700,3950)","2","mstr_standard","I32";
;
HDL_TAP"TRUE"
BODY_TYPE"PLUMBING"
CDS_LIB"mstr_standard";
"B \NAC \NWC"2;
"S \NAC"
BN"5"143;
%"TAP"
"6","(700,3850)","2","mstr_standard","I33";
;
HDL_TAP"TRUE"
BODY_TYPE"PLUMBING"
CDS_LIB"mstr_standard";
"B \NAC \NWC"2;
"S \NAC"
BN"4"145;
%"TAP"
"6","(700,3750)","2","mstr_standard","I34";
;
HDL_TAP"TRUE"
BODY_TYPE"PLUMBING"
CDS_LIB"mstr_standard";
"B \NAC \NWC"2;
"S \NAC"
BN"3"147;
%"TAP"
"6","(900,3500)","2","mstr_standard","I35";
;
HDL_TAP"TRUE"
BODY_TYPE"PLUMBING"
CDS_LIB"mstr_standard";
"B \NAC \NWC"1;
"S \NAC"
BN"1"152;
%"TAP"
"6","(900,3600)","2","mstr_standard","I36";
;
HDL_TAP"TRUE"
BODY_TYPE"PLUMBING"
CDS_LIB"mstr_standard";
"B \NAC \NWC"1;
"S \NAC"
BN"2"150;
%"TAP"
"6","(900,3700)","2","mstr_standard","I37";
;
HDL_TAP"TRUE"
BODY_TYPE"PLUMBING"
CDS_LIB"mstr_standard";
"B \NAC \NWC"1;
"S \NAC"
BN"3"148;
%"TAP"
"6","(700,3650)","2","mstr_standard","I38";
;
HDL_TAP"TRUE"
BODY_TYPE"PLUMBING"
CDS_LIB"mstr_standard";
"B \NAC \NWC"2;
"S \NAC"
BN"2"149;
%"TAP"
"6","(700,3550)","2","mstr_standard","I39";
;
HDL_TAP"TRUE"
BODY_TYPE"PLUMBING"
CDS_LIB"mstr_standard";
"B \NAC \NWC"2;
"S \NAC"
BN"1"151;
%"TAP"
"6","(700,5150)","2","mstr_standard","I4";
;
HDL_TAP"TRUE"
BODY_TYPE"PLUMBING"
CDS_LIB"mstr_standard";
"B \NAC \NWC"2;
"S \NAC"
BN"17"176;
%"TAP"
"6","(900,3400)","2","mstr_standard","I40";
;
HDL_TAP"TRUE"
BODY_TYPE"PLUMBING"
CDS_LIB"mstr_standard";
"B \NAC \NWC"1;
"S \NAC"
BN"0"154;
%"TAP"
"6","(700,3450)","2","mstr_standard","I41";
;
HDL_TAP"TRUE"
BODY_TYPE"PLUMBING"
CDS_LIB"mstr_standard";
"B \NAC \NWC"2;
"S \NAC"
BN"0"153;
%"GND"
"1","(2500,1300)","2","mstr_symbols","I42";
;
HDL_POWER"GND"
ROOM"DDR4_CH_A"
BODY_TYPE"PLUMBING"
SIZE"1B"
CDS_LIB"mstr_symbols"
BOM_COST"MEM"
VOLTAGE"0";
"A\NAC"20;
%"SCONN288_H44441004"
"3","(1800,2600)","0","mstr_sconn","I43";
;
CDS_SEC"3"
ROOM"DDR4_CH_B"
CDS_LOCATION"J4G2"
SEC"3"
SEC_TYPE"PIP"
CDS_LIB"mstr_sconn"
BOM_COST"MEM"
PACK_TYPE"PIP"
MATERIAL"SCONN"
PART_NUMBER"H44441-004"
LOCATION"J4G2";
"VSS<93>"
$PN"2"21;
"VSS<92>"
$PN"4"21;
"VSS<91>"
$PN"6"21;
"VSS<90>"
$PN"9"21;
"VSS<89>"
$PN"11"21;
"VSS<88>"
$PN"13"21;
"VSS<0>"
$PN"283"20;
"VSS<1>"
$PN"281"20;
"VSS<2>"
$PN"279"20;
"VSS<3>"
$PN"276"20;
"VSS<4>"
$PN"274"20;
"VSS<5>"
$PN"272"20;
"VSS<6>"
$PN"270"20;
"VSS<7>"
$PN"268"20;
"VSS<8>"
$PN"265"20;
"VSS<9>"
$PN"263"20;
"VSS<10>"
$PN"261"20;
"VSS<11>"
$PN"259"20;
"VSS<12>"
$PN"257"20;
"VSS<13>"
$PN"254"20;
"VSS<14>"
$PN"252"20;
"VSS<15>"
$PN"250"20;
"VSS<16>"
$PN"248"20;
"VSS<17>"
$PN"246"20;
"VSS<18>"
$PN"243"20;
"VSS<19>"
$PN"241"20;
"VSS<20>"
$PN"239"20;
"VSS<21>"
$PN"202"20;
"VSS<22>"
$PN"200"20;
"VSS<23>"
$PN"198"20;
"VSS<24>"
$PN"195"20;
"VSS<25>"
$PN"193"20;
"VSS<26>"
$PN"191"20;
"VSS<27>"
$PN"189"20;
"VSS<28>"
$PN"187"20;
"VSS<29>"
$PN"184"20;
"VSS<30>"
$PN"182"20;
"VSS<31>"
$PN"180"20;
"VSS<32>"
$PN"178"20;
"VSS<33>"
$PN"176"20;
"VSS<34>"
$PN"173"20;
"VSS<35>"
$PN"171"20;
"VSS<36>"
$PN"169"20;
"VSS<37>"
$PN"167"20;
"VSS<38>"
$PN"165"20;
"VSS<39>"
$PN"162"20;
"VSS<40>"
$PN"160"20;
"VSS<41>"
$PN"158"20;
"VSS<42>"
$PN"156"20;
"VSS<43>"
$PN"154"20;
"VSS<44>"
$PN"151"20;
"VSS<47>"
$PN"138"21;
"VSS<48>"
$PN"136"21;
"VSS<49>"
$PN"134"21;
"VSS<50>"
$PN"131"21;
"VSS<51>"
$PN"129"21;
"VSS<52>"
$PN"127"21;
"VSS<53>"
$PN"125"21;
"VSS<54>"
$PN"123"21;
"VSS<55>"
$PN"120"21;
"VSS<56>"
$PN"118"21;
"VSS<57>"
$PN"116"21;
"VSS<58>"
$PN"114"21;
"VSS<59>"
$PN"112"21;
"VSS<60>"
$PN"109"21;
"VSS<61>"
$PN"107"21;
"VSS<62>"
$PN"105"21;
"VSS<63>"
$PN"103"21;
"VSS<64>"
$PN"101"21;
"VSS<65>"
$PN"98"21;
"VSS<66>"
$PN"96"21;
"VSS<67>"
$PN"94"21;
"VSS<68>"
$PN"57"21;
"VSS<69>"
$PN"55"21;
"VSS<70>"
$PN"53"21;
"VSS<71>"
$PN"50"21;
"VSS<72>"
$PN"48"21;
"VSS<73>"
$PN"46"21;
"VSS<74>"
$PN"44"21;
"VSS<75>"
$PN"42"21;
"VSS<76>"
$PN"39"21;
"VSS<77>"
$PN"37"21;
"VSS<78>"
$PN"35"21;
"VSS<79>"
$PN"33"21;
"VSS<80>"
$PN"31"21;
"VSS<81>"
$PN"28"21;
"VSS<82>"
$PN"26"21;
"VSS<83>"
$PN"24"21;
"VSS<84>"
$PN"22"21;
"VSS<85>"
$PN"20"21;
"VSS<86>"
$PN"17"21;
"VSS<87>"
$PN"15"21;
"VSS<45>"
$PN"149"20;
"VSS<46>"
$PN"147"20;
%"GND"
"1","(1100,1300)","2","mstr_symbols","I44";
;
HDL_POWER"GND"
ROOM"DDR4_CH_A"
BODY_TYPE"PLUMBING"
SIZE"1B"
CDS_LIB"mstr_symbols"
BOM_COST"MEM"
VOLTAGE"0";
"A\NAC"21;
%"TAP"
"6","(-1700,4600)","2","mstr_standard","I46";
;
HDL_TAP"TRUE"
BODY_TYPE"PLUMBING"
CDS_LIB"mstr_standard";
"B \NAC \NWC"4;
"S \NAC"
BN"62"130;
%"TAP"
"6","(-1700,4550)","2","mstr_standard","I47";
;
HDL_TAP"TRUE"
BODY_TYPE"PLUMBING"
CDS_LIB"mstr_standard";
"B \NAC \NWC"4;
"S \NAC"
BN"63"131;
%"TAP"
"6","(-1700,4400)","2","mstr_standard","I48";
;
HDL_TAP"TRUE"
BODY_TYPE"PLUMBING"
CDS_LIB"mstr_standard";
"B \NAC \NWC"4;
"S \NAC"
BN"58"139;
%"TAP"
"6","(-1700,4450)","2","mstr_standard","I49";
;
HDL_TAP"TRUE"
BODY_TYPE"PLUMBING"
CDS_LIB"mstr_standard";
"B \NAC \NWC"4;
"S \NAC"
BN"61"140;
%"TAP"
"6","(700,5050)","2","mstr_standard","I5";
;
HDL_TAP"TRUE"
BODY_TYPE"PLUMBING"
CDS_LIB"mstr_standard";
"B \NAC \NWC"2;
"S \NAC"
BN"16"162;
%"TAP"
"6","(-1700,4500)","2","mstr_standard","I50";
;
HDL_TAP"TRUE"
BODY_TYPE"PLUMBING"
CDS_LIB"mstr_standard";
"B \NAC \NWC"4;
"S \NAC"
BN"60"132;
%"TAP"
"6","(-1700,4300)","2","mstr_standard","I51";
;
HDL_TAP"TRUE"
BODY_TYPE"PLUMBING"
CDS_LIB"mstr_standard";
"B \NAC \NWC"4;
"S \NAC"
BN"56"136;
%"TAP"
"6","(-1700,4350)","2","mstr_standard","I52";
;
HDL_TAP"TRUE"
BODY_TYPE"PLUMBING"
CDS_LIB"mstr_standard";
"B \NAC \NWC"4;
"S \NAC"
BN"59"135;
%"TAP"
"6","(-1700,4150)","2","mstr_standard","I53";
;
HDL_TAP"TRUE"
BODY_TYPE"PLUMBING"
CDS_LIB"mstr_standard";
"B \NAC \NWC"4;
"S \NAC"
BN"55"134;
%"TAP"
"6","(-1700,4200)","2","mstr_standard","I54";
;
HDL_TAP"TRUE"
BODY_TYPE"PLUMBING"
CDS_LIB"mstr_standard";
"B \NAC \NWC"4;
"S \NAC"
BN"54"137;
%"TAP"
"6","(-1700,4250)","2","mstr_standard","I55";
;
HDL_TAP"TRUE"
BODY_TYPE"PLUMBING"
CDS_LIB"mstr_standard";
"B \NAC \NWC"4;
"S \NAC"
BN"57"138;
%"TAP"
"6","(-1700,4050)","2","mstr_standard","I56";
;
HDL_TAP"TRUE"
BODY_TYPE"PLUMBING"
CDS_LIB"mstr_standard";
"B \NAC \NWC"4;
"S \NAC"
BN"53"114;
%"TAP"
"6","(-1700,4100)","2","mstr_standard","I57";
;
HDL_TAP"TRUE"
BODY_TYPE"PLUMBING"
CDS_LIB"mstr_standard";
"B \NAC \NWC"4;
"S \NAC"
BN"52"133;
%"TAP"
"6","(-1700,4000)","2","mstr_standard","I58";
;
HDL_TAP"TRUE"
BODY_TYPE"PLUMBING"
CDS_LIB"mstr_standard";
"B \NAC \NWC"4;
"S \NAC"
BN"50"113;
%"TAP"
"6","(-1700,3950)","2","mstr_standard","I59";
;
HDL_TAP"TRUE"
BODY_TYPE"PLUMBING"
CDS_LIB"mstr_standard";
"B \NAC \NWC"4;
"S \NAC"
BN"51"112;
%"TAP"
"6","(900,4900)","2","mstr_standard","I6";
;
HDL_TAP"TRUE"
BODY_TYPE"PLUMBING"
CDS_LIB"mstr_standard";
"B \NAC \NWC"1;
"S \NAC"
BN"15"165;
%"TAP"
"6","(-1700,3900)","2","mstr_standard","I60";
;
HDL_TAP"TRUE"
BODY_TYPE"PLUMBING"
CDS_LIB"mstr_standard";
"B \NAC \NWC"4;
"S \NAC"
BN"48"111;
%"SCONN288_H44441004"
"2","(0,4300)","0","mstr_sconn","I61";
;
CDS_SEC"2"
ROOM"DDR4_CH_B"
CDS_LOCATION"J4G2"
SEC"2"
SEC_TYPE"PIP"
CDS_LIB"mstr_sconn"
BOM_COST"MEM"
PACK_TYPE"PIP"
MATERIAL"SCONN"
PART_NUMBER"H44441-004"
LOCATION"J4G2";
"DQS17P"
$PN"51"176;
"DQS9P"
$PN"7"155;
"DQS9N"
$PN"8"156;
"DQS8P"
$PN"197"157;
"DQS8N"
$PN"196"158;
"DQS7P"
$PN"278"159;
"DQS7N"
$PN"277"160;
"DQS6P"
$PN"267"141;
"DQS6N"
$PN"266"142;
"DQS5P"
$PN"256"143;
"DQS5N"
$PN"255"144;
"DQS4P"
$PN"245"145;
"DQS4N"
$PN"244"146;
"DQS3P"
$PN"186"147;
"DQS3N"
$PN"185"148;
"DQS2P"
$PN"175"149;
"DQS2N"
$PN"174"150;
"DQS1P"
$PN"164"151;
"DQS1N"
$PN"163"152;
"DQS17N"
$PN"52"161;
"DQS16P"
$PN"132"162;
"DQS16N"
$PN"133"163;
"DQS15P"
$PN"121"164;
"DQS15N"
$PN"122"165;
"DQS14P"
$PN"110"166;
"DQS14N"
$PN"111"167;
"DQS13P"
$PN"99"168;
"DQS13N"
$PN"100"169;
"DQS12P"
$PN"40"170;
"DQS12N"
$PN"41"171;
"DQS11P"
$PN"29"172;
"DQS11N"
$PN"30"173;
"DQS10P"
$PN"18"174;
"DQS10N"
$PN"19"175;
"DQS0P"
$PN"153"153;
"DQS0N"
$PN"152"154;
%"TAP"
"6","(-1700,3750)","2","mstr_standard","I62";
;
HDL_TAP"TRUE"
BODY_TYPE"PLUMBING"
CDS_LIB"mstr_standard";
"B \NAC \NWC"4;
"S \NAC"
BN"47"118;
%"TAP"
"6","(-1700,3800)","2","mstr_standard","I63";
;
HDL_TAP"TRUE"
BODY_TYPE"PLUMBING"
CDS_LIB"mstr_standard";
"B \NAC \NWC"4;
"S \NAC"
BN"46"109;
%"TAP"
"6","(-1700,3850)","2","mstr_standard","I64";
;
HDL_TAP"TRUE"
BODY_TYPE"PLUMBING"
CDS_LIB"mstr_standard";
"B \NAC \NWC"4;
"S \NAC"
BN"49"110;
%"TAP"
"6","(-1700,3700)","2","mstr_standard","I65";
;
HDL_TAP"TRUE"
BODY_TYPE"PLUMBING"
CDS_LIB"mstr_standard";
"B \NAC \NWC"4;
"S \NAC"
BN"44"117;
%"TAP"
"6","(-1700,3650)","2","mstr_standard","I66";
;
HDL_TAP"TRUE"
BODY_TYPE"PLUMBING"
CDS_LIB"mstr_standard";
"B \NAC \NWC"4;
"S \NAC"
BN"45"116;
%"TAP"
"6","(-1700,3600)","2","mstr_standard","I67";
;
HDL_TAP"TRUE"
BODY_TYPE"PLUMBING"
CDS_LIB"mstr_standard";
"B \NAC \NWC"4;
"S \NAC"
BN"42"115;
%"TAP"
"6","(-1700,3550)","2","mstr_standard","I68";
;
HDL_TAP"TRUE"
BODY_TYPE"PLUMBING"
CDS_LIB"mstr_standard";
"B \NAC \NWC"4;
"S \NAC"
BN"43"108;
%"TAP"
"6","(-1700,3500)","2","mstr_standard","I69";
;
HDL_TAP"TRUE"
BODY_TYPE"PLUMBING"
CDS_LIB"mstr_standard";
"B \NAC \NWC"4;
"S \NAC"
BN"40"107;
%"TAP"
"6","(900,5000)","2","mstr_standard","I7";
;
HDL_TAP"TRUE"
BODY_TYPE"PLUMBING"
CDS_LIB"mstr_standard";
"B \NAC \NWC"1;
"S \NAC"
BN"16"163;
%"TAP"
"6","(-1700,3400)","2","mstr_standard","I70";
;
HDL_TAP"TRUE"
BODY_TYPE"PLUMBING"
CDS_LIB"mstr_standard";
"B \NAC \NWC"4;
"S \NAC"
BN"38"105;
%"TAP"
"6","(-1700,3450)","2","mstr_standard","I71";
;
HDL_TAP"TRUE"
BODY_TYPE"PLUMBING"
CDS_LIB"mstr_standard";
"B \NAC \NWC"4;
"S \NAC"
BN"41"106;
%"TAP"
"6","(-1700,3250)","2","mstr_standard","I72";
;
HDL_TAP"TRUE"
BODY_TYPE"PLUMBING"
CDS_LIB"mstr_standard";
"B \NAC \NWC"4;
"S \NAC"
BN"37"100;
%"TAP"
"6","(-1700,3300)","2","mstr_standard","I73";
;
HDL_TAP"TRUE"
BODY_TYPE"PLUMBING"
CDS_LIB"mstr_standard";
"B \NAC \NWC"4;
"S \NAC"
BN"36"104;
%"TAP"
"6","(-1700,3350)","2","mstr_standard","I74";
;
HDL_TAP"TRUE"
BODY_TYPE"PLUMBING"
CDS_LIB"mstr_standard";
"B \NAC \NWC"4;
"S \NAC"
BN"39"99;
%"TAP"
"6","(-1700,3150)","2","mstr_standard","I75";
;
HDL_TAP"TRUE"
BODY_TYPE"PLUMBING"
CDS_LIB"mstr_standard";
"B \NAC \NWC"4;
"S \NAC"
BN"35"103;
%"TAP"
"6","(-1700,3200)","2","mstr_standard","I76";
;
HDL_TAP"TRUE"
BODY_TYPE"PLUMBING"
CDS_LIB"mstr_standard";
"B \NAC \NWC"4;
"S \NAC"
BN"34"101;
%"TAP"
"6","(-1700,3100)","2","mstr_standard","I77";
;
HDL_TAP"TRUE"
BODY_TYPE"PLUMBING"
CDS_LIB"mstr_standard";
"B \NAC \NWC"4;
"S \NAC"
BN"32"102;
%"TAP"
"6","(-1700,3050)","2","mstr_standard","I78";
;
HDL_TAP"TRUE"
BODY_TYPE"PLUMBING"
CDS_LIB"mstr_standard";
"B \NAC \NWC"4;
"S \NAC"
BN"33"96;
%"TAP"
"6","(-1700,3000)","2","mstr_standard","I79";
;
HDL_TAP"TRUE"
BODY_TYPE"PLUMBING"
CDS_LIB"mstr_standard";
"B \NAC \NWC"4;
"S \NAC"
BN"30"95;
%"TAP"
"6","(900,4800)","2","mstr_standard","I8";
;
HDL_TAP"TRUE"
BODY_TYPE"PLUMBING"
CDS_LIB"mstr_standard";
"B \NAC \NWC"1;
"S \NAC"
BN"14"167;
%"TAP"
"6","(-1700,2850)","2","mstr_standard","I80";
;
HDL_TAP"TRUE"
BODY_TYPE"PLUMBING"
CDS_LIB"mstr_standard";
"B \NAC \NWC"4;
"S \NAC"
BN"29"97;
%"TAP"
"6","(-1700,2900)","2","mstr_standard","I81";
;
HDL_TAP"TRUE"
BODY_TYPE"PLUMBING"
CDS_LIB"mstr_standard";
"B \NAC \NWC"4;
"S \NAC"
BN"28"98;
%"TAP"
"6","(-1700,2950)","2","mstr_standard","I82";
;
HDL_TAP"TRUE"
BODY_TYPE"PLUMBING"
CDS_LIB"mstr_standard";
"B \NAC \NWC"4;
"S \NAC"
BN"31"94;
%"TAP"
"6","(-1700,2800)","2","mstr_standard","I83";
;
HDL_TAP"TRUE"
BODY_TYPE"PLUMBING"
CDS_LIB"mstr_standard";
"B \NAC \NWC"4;
"S \NAC"
BN"26"90;
%"TAP"
"6","(-1700,2750)","2","mstr_standard","I84";
;
HDL_TAP"TRUE"
BODY_TYPE"PLUMBING"
CDS_LIB"mstr_standard";
"B \NAC \NWC"4;
"S \NAC"
BN"27"89;
%"TAP"
"6","(-1700,2600)","2","mstr_standard","I85";
;
HDL_TAP"TRUE"
BODY_TYPE"PLUMBING"
CDS_LIB"mstr_standard";
"B \NAC \NWC"4;
"S \NAC"
BN"22"91;
%"TAP"
"6","(-1700,2700)","2","mstr_standard","I86";
;
HDL_TAP"TRUE"
BODY_TYPE"PLUMBING"
CDS_LIB"mstr_standard";
"B \NAC \NWC"4;
"S \NAC"
BN"24"93;
%"TAP"
"6","(-1700,2650)","2","mstr_standard","I87";
;
HDL_TAP"TRUE"
BODY_TYPE"PLUMBING"
CDS_LIB"mstr_standard";
"B \NAC \NWC"4;
"S \NAC"
BN"25"92;
%"TAP"
"6","(-1700,2500)","2","mstr_standard","I88";
;
HDL_TAP"TRUE"
BODY_TYPE"PLUMBING"
CDS_LIB"mstr_standard";
"B \NAC \NWC"4;
"S \NAC"
BN"20"86;
%"TAP"
"6","(-1700,2550)","2","mstr_standard","I89";
;
HDL_TAP"TRUE"
BODY_TYPE"PLUMBING"
CDS_LIB"mstr_standard";
"B \NAC \NWC"4;
"S \NAC"
BN"23"87;
%"TAP"
"6","(700,4950)","2","mstr_standard","I9";
;
HDL_TAP"TRUE"
BODY_TYPE"PLUMBING"
CDS_LIB"mstr_standard";
"B \NAC \NWC"2;
"S \NAC"
BN"15"164;
%"TAP"
"6","(-1700,2450)","2","mstr_standard","I90";
;
HDL_TAP"TRUE"
BODY_TYPE"PLUMBING"
CDS_LIB"mstr_standard";
"B \NAC \NWC"4;
"S \NAC"
BN"21"88;
%"TAP"
"6","(-1700,2400)","2","mstr_standard","I91";
;
HDL_TAP"TRUE"
BODY_TYPE"PLUMBING"
CDS_LIB"mstr_standard";
"B \NAC \NWC"4;
"S \NAC"
BN"18"85;
%"TAP"
"6","(-1700,2350)","2","mstr_standard","I92";
;
HDL_TAP"TRUE"
BODY_TYPE"PLUMBING"
CDS_LIB"mstr_standard";
"B \NAC \NWC"4;
"S \NAC"
BN"19"84;
%"TAP"
"6","(-1700,2250)","2","mstr_standard","I93";
;
HDL_TAP"TRUE"
BODY_TYPE"PLUMBING"
CDS_LIB"mstr_standard";
"B \NAC \NWC"4;
"S \NAC"
BN"17"83;
%"TAP"
"6","(-1700,2300)","2","mstr_standard","I94";
;
HDL_TAP"TRUE"
BODY_TYPE"PLUMBING"
CDS_LIB"mstr_standard";
"B \NAC \NWC"4;
"S \NAC"
BN"16"78;
%"TAP"
"6","(-1700,2100)","2","mstr_standard","I95";
;
HDL_TAP"TRUE"
BODY_TYPE"PLUMBING"
CDS_LIB"mstr_standard";
"B \NAC \NWC"4;
"S \NAC"
BN"12"81;
%"TAP"
"6","(-1700,2150)","2","mstr_standard","I96";
;
HDL_TAP"TRUE"
BODY_TYPE"PLUMBING"
CDS_LIB"mstr_standard";
"B \NAC \NWC"4;
"S \NAC"
BN"15"82;
%"TAP"
"6","(-1700,2200)","2","mstr_standard","I97";
;
HDL_TAP"TRUE"
BODY_TYPE"PLUMBING"
CDS_LIB"mstr_standard";
"B \NAC \NWC"4;
"S \NAC"
BN"14"79;
%"TAP"
"6","(-1700,2000)","2","mstr_standard","I98";
;
HDL_TAP"TRUE"
BODY_TYPE"PLUMBING"
CDS_LIB"mstr_standard";
"B \NAC \NWC"4;
"S \NAC"
BN"10"76;
%"TAP"
"6","(-1700,2050)","2","mstr_standard","I99";
;
HDL_TAP"TRUE"
BODY_TYPE"PLUMBING"
CDS_LIB"mstr_standard";
"B \NAC \NWC"4;
"S \NAC"
BN"13"80;
END.
